(kicad_pcb
	(version 20260206)
	(generator "pcbnew")
	(generator_version "10.0")
	(general
		(thickness 1.6)
		(legacy_teardrops no)
	)
	(paper "A4")
	(title_block
		(title "03242023_DA0F0TMBIJ0_F0T_Motherboard_J_brd_V01_OCP.brd")
		(comment 1 "Grand Teton / footprints 834-840 of 6105")
	)
	(layers
		(0 "F.Cu" signal "TOP")
		(4 "In1.Cu" signal "GND")
		(6 "In2.Cu" signal "IN1")
		(8 "In3.Cu" signal "GND1")
		(10 "In4.Cu" signal "IN2")
		(12 "In5.Cu" signal "GND2")
		(14 "In6.Cu" signal "IN3")
		(16 "In7.Cu" signal "GND3")
		(18 "In8.Cu" signal "VCC")
		(20 "In9.Cu" signal "VCC1")
		(22 "In10.Cu" signal "GND4")
		(24 "In11.Cu" signal "IN4")
		(26 "In12.Cu" signal "GND5")
		(28 "In13.Cu" signal "IN5")
		(30 "In14.Cu" signal "GND6")
		(32 "In15.Cu" signal "IN6")
		(34 "In16.Cu" signal "GND7")
		(2 "B.Cu" signal "BOTTOM")
		(9 "F.Adhes" user "F.Adhesive")
		(11 "B.Adhes" user "B.Adhesive")
		(13 "F.Paste" user "Package Geometry/Pastemask Top")
		(15 "B.Paste" user "Package Geometry/Pastemask Bottom")
		(5 "F.SilkS" user "Ref Des/Silkscreen Top")
		(7 "B.SilkS" user "Ref Des/Silkscreen Bottom")
		(1 "F.Mask" user "Board Geometry/Soldermask Top")
		(3 "B.Mask" user "Board Geometry/Soldermask Bottom")
		(17 "Dwgs.User" user "User.Drawings")
		(19 "Cmts.User" user "User.Comments")
		(21 "Eco1.User" user "User.Eco1")
		(23 "Eco2.User" user "User.Eco2")
		(25 "Edge.Cuts" user "Board Geometry/Outline")
		(27 "Margin" user)
		(31 "F.CrtYd" user "Package Geometry/Place Bound Top")
		(29 "B.CrtYd" user "Package Geometry/Place Bound Bottom")
		(35 "F.Fab" user "Ref Des/Assembly Top")
		(33 "B.Fab" user "Ref Des/Assembly Bottom")
	)
	(footprint ""
		(layer "F.Cu")
		(at 216.065608 -399.743422 180)
		(property "Reference" "PC2350"
			(at 0 0 180)
			(layer "F.SilkS")
			(hide yes)
			(effects
				(font
					(size 1.27 1.27)
				)
			)
		)
		(property "Value" ""
			(at 0 0 180)
			(layer "F.Fab")
			(effects
				(font
					(size 1.27 1.27)
				)
			)
		)
		(duplicate_pad_numbers_are_jumpers no)
		(fp_line
			(start 0.7874 0.4064)
			(end -0.7874 0.4064)
			(stroke
				(width 0.1524)
				(type default)
			)
			(layer "F.SilkS")
		)
		(fp_line
			(start 0.7874 -0.4064)
			(end 0.7874 0.4064)
			(stroke
				(width 0.1524)
				(type default)
			)
			(layer "F.SilkS")
		)
		(fp_line
			(start -0.7874 0.4064)
			(end -0.7874 -0.4064)
			(stroke
				(width 0.1524)
				(type default)
			)
			(layer "F.SilkS")
		)
		(fp_line
			(start -0.7874 -0.4064)
			(end 0.7874 -0.4064)
			(stroke
				(width 0.1524)
				(type default)
			)
			(layer "F.SilkS")
		)
		(fp_line
			(start 0.67945 0.3048)
			(end 0.120396 0.3048)
			(stroke
				(width 0.1)
				(type default)
			)
			(layer "F.Fab")
		)
		(fp_line
			(start 0.67945 -0.3048)
			(end 0.67945 0.3048)
			(stroke
				(width 0.1)
				(type default)
			)
			(layer "F.Fab")
		)
		(fp_line
			(start 0.12065 -0.2794)
			(end 0.12065 -0.3048)
			(stroke
				(width 0.1)
				(type default)
			)
			(layer "F.Fab")
		)
		(fp_line
			(start 0.12065 -0.3048)
			(end 0.67945 -0.3048)
			(stroke
				(width 0.1)
				(type default)
			)
			(layer "F.Fab")
		)
		(fp_line
			(start 0.120396 0.3048)
			(end 0.120396 0.2794)
			(stroke
				(width 0.1)
				(type default)
			)
			(layer "F.Fab")
		)
		(fp_line
			(start 0.120396 0.2794)
			(end -0.12065 0.2794)
			(stroke
				(width 0.1)
				(type default)
			)
			(layer "F.Fab")
		)
		(fp_line
			(start -0.12065 0.3048)
			(end -0.67945 0.3048)
			(stroke
				(width 0.1)
				(type default)
			)
			(layer "F.Fab")
		)
		(fp_line
			(start -0.12065 0.2794)
			(end -0.12065 0.3048)
			(stroke
				(width 0.1)
				(type default)
			)
			(layer "F.Fab")
		)
		(fp_line
			(start -0.12065 -0.2794)
			(end 0.12065 -0.2794)
			(stroke
				(width 0.1)
				(type default)
			)
			(layer "F.Fab")
		)
		(fp_line
			(start -0.12065 -0.305054)
			(end -0.12065 -0.2794)
			(stroke
				(width 0.1)
				(type default)
			)
			(layer "F.Fab")
		)
		(fp_line
			(start -0.67945 0.3048)
			(end -0.67945 -0.305054)
			(stroke
				(width 0.1)
				(type default)
			)
			(layer "F.Fab")
		)
		(fp_line
			(start -0.67945 -0.305054)
			(end -0.12065 -0.305054)
			(stroke
				(width 0.1)
				(type default)
			)
			(layer "F.Fab")
		)
		(pad "1" smd circle
			(at -0.40005 0 180)
			(size 0 0)
			(layers "F.Cu" "F.Mask" "F.Paste")
			(net "HSC_OCREF")
		)
		(pad "2" smd circle
			(at 0.40005 0 180)
			(size 0 0)
			(layers "F.Cu" "F.Mask" "F.Paste")
			(net "AGND_HSC")
		)
	)
	(footprint ""
		(layer "F.Cu")
		(at 413.282384 -16.088614 90)
		(property "Reference" "C854"
			(at 0 0 90)
			(layer "F.SilkS")
			(hide yes)
			(effects
				(font
					(size 1.27 1.27)
				)
			)
		)
		(property "Value" ""
			(at 0 0 90)
			(layer "F.Fab")
			(effects
				(font
					(size 1.27 1.27)
				)
			)
		)
		(duplicate_pad_numbers_are_jumpers no)
		(fp_line
			(start 0.299974 -0.150114)
			(end 0.299974 0.150114)
			(stroke
				(width 0.1)
				(type default)
			)
			(layer "F.Fab")
		)
		(fp_line
			(start -0.299974 -0.150114)
			(end 0.299974 -0.150114)
			(stroke
				(width 0.1)
				(type default)
			)
			(layer "F.Fab")
		)
		(fp_line
			(start 0.299974 0.150114)
			(end -0.299974 0.150114)
			(stroke
				(width 0.1)
				(type default)
			)
			(layer "F.Fab")
		)
		(fp_line
			(start -0.299974 0.150114)
			(end -0.299974 -0.150114)
			(stroke
				(width 0.1)
				(type default)
			)
			(layer "F.Fab")
		)
		(pad "1" smd rect
			(at -0.2667 0 90)
			(size 0.3048 0.381)
			(layers "F.Cu" "F.Mask" "F.Paste")
			(net "P5E_CPU0_PE1_TX_C_DN<7>")
		)
		(pad "2" smd rect
			(at 0.2667 0 90)
			(size 0.3048 0.381)
			(layers "F.Cu" "F.Mask" "F.Paste")
			(net "P5E_CPU0_PE1_TX_DN<7>")
		)
	)
	(footprint ""
		(layer "F.Cu")
		(at 260.561582 -77.549502)
		(property "Reference" "PC1223"
			(at 0 0 0)
			(layer "F.SilkS")
			(hide yes)
			(effects
				(font
					(size 1.27 1.27)
				)
			)
		)
		(property "Value" ""
			(at 0 0 0)
			(layer "F.Fab")
			(effects
				(font
					(size 1.27 1.27)
				)
			)
		)
		(duplicate_pad_numbers_are_jumpers no)
		(fp_line
			(start -0.7874 -0.4064)
			(end 0.7874 -0.4064)
			(stroke
				(width 0.1524)
				(type default)
			)
			(layer "F.SilkS")
		)
		(fp_line
			(start -0.7874 0.4064)
			(end -0.7874 -0.4064)
			(stroke
				(width 0.1524)
				(type default)
			)
			(layer "F.SilkS")
		)
		(fp_line
			(start 0.7874 -0.4064)
			(end 0.7874 0.4064)
			(stroke
				(width 0.1524)
				(type default)
			)
			(layer "F.SilkS")
		)
		(fp_line
			(start 0.7874 0.4064)
			(end -0.7874 0.4064)
			(stroke
				(width 0.1524)
				(type default)
			)
			(layer "F.SilkS")
		)
		(fp_line
			(start -0.67945 -0.305054)
			(end -0.12065 -0.305054)
			(stroke
				(width 0.1)
				(type default)
			)
			(layer "F.Fab")
		)
		(fp_line
			(start -0.67945 0.3048)
			(end -0.67945 -0.305054)
			(stroke
				(width 0.1)
				(type default)
			)
			(layer "F.Fab")
		)
		(fp_line
			(start -0.12065 -0.305054)
			(end -0.12065 -0.2794)
			(stroke
				(width 0.1)
				(type default)
			)
			(layer "F.Fab")
		)
		(fp_line
			(start -0.12065 -0.2794)
			(end 0.12065 -0.2794)
			(stroke
				(width 0.1)
				(type default)
			)
			(layer "F.Fab")
		)
		(fp_line
			(start -0.12065 0.2794)
			(end -0.12065 0.3048)
			(stroke
				(width 0.1)
				(type default)
			)
			(layer "F.Fab")
		)
		(fp_line
			(start -0.12065 0.3048)
			(end -0.67945 0.3048)
			(stroke
				(width 0.1)
				(type default)
			)
			(layer "F.Fab")
		)
		(fp_line
			(start 0.120396 0.2794)
			(end -0.12065 0.2794)
			(stroke
				(width 0.1)
				(type default)
			)
			(layer "F.Fab")
		)
		(fp_line
			(start 0.120396 0.3048)
			(end 0.120396 0.2794)
			(stroke
				(width 0.1)
				(type default)
			)
			(layer "F.Fab")
		)
		(fp_line
			(start 0.12065 -0.3048)
			(end 0.67945 -0.3048)
			(stroke
				(width 0.1)
				(type default)
			)
			(layer "F.Fab")
		)
		(fp_line
			(start 0.12065 -0.2794)
			(end 0.12065 -0.3048)
			(stroke
				(width 0.1)
				(type default)
			)
			(layer "F.Fab")
		)
		(fp_line
			(start 0.67945 -0.3048)
			(end 0.67945 0.3048)
			(stroke
				(width 0.1)
				(type default)
			)
			(layer "F.Fab")
		)
		(fp_line
			(start 0.67945 0.3048)
			(end 0.120396 0.3048)
			(stroke
				(width 0.1)
				(type default)
			)
			(layer "F.Fab")
		)
		(pad "1" smd circle
			(at -0.40005 0)
			(size 0 0)
			(layers "F.Cu" "F.Mask" "F.Paste")
			(net "P1V05_PCH_AUX_FB")
		)
		(pad "2" smd circle
			(at 0.40005 0)
			(size 0 0)
			(layers "F.Cu" "F.Mask" "F.Paste")
			(net "SH_P1V05_PCH_AUX_P")
		)
	)
	(footprint ""
		(layer "F.Cu")
		(at 460.49692 -127.627888)
		(property "Reference" "H29"
			(at -5.78358 -6.25729 0)
			(unlocked yes)
			(layer "F.SilkS")
			(effects
				(font
					(size 0.7874 0.5842)
					(thickness 0.1524)
				)
				(justify left)
			)
		)
		(property "Value" ""
			(at 0 0 0)
			(layer "F.Fab")
			(effects
				(font
					(size 1.27 1.27)
				)
			)
		)
		(duplicate_pad_numbers_are_jumpers no)
		(fp_circle
			(center 0 0)
			(end 2.4003 0)
			(stroke
				(width 0.1524)
				(type default)
			)
			(fill no)
			(layer "F.SilkS")
		)
		(fp_arc
			(start 5.668518 3.363214)
			(mid -6.590047 -0.148895)
			(end 5.814314 -3.104896)
			(stroke
				(width 0.1524)
				(type default)
			)
			(layer "B.SilkS")
		)
		(fp_circle
			(center 0 0)
			(end 6.5913 0)
			(stroke
				(width 0.1)
				(type default)
			)
			(fill no)
			(layer "B.Fab")
		)
		(fp_circle
			(center 0 0)
			(end 2.4003 0)
			(stroke
				(width 0.1)
				(type default)
			)
			(fill no)
			(layer "F.Fab")
		)
		(pad "" np_thru_hole circle
			(at 0 0)
			(size 3.175 3.175)
			(drill 3.175)
			(layers "*.Cu" "*.Mask")
			(clearance 0.381)
			(thermal_gap 0.381)
		)
		(zone
			(layers "F.Cu" "B.Cu" "In1.Cu" "In2.Cu" "In3.Cu" "In4.Cu" "In5.Cu" "In6.Cu"
				"In7.Cu" "In8.Cu" "In9.Cu" "In10.Cu" "In11.Cu" "In12.Cu" "In13.Cu" "In14.Cu"
				"In15.Cu" "In16.Cu"
			)
			(hatch none 0.5)
			(connect_pads
				(clearance 0)
			)
			(min_thickness 0.25)
			(keepout
				(tracks not_allowed)
				(vias allowed)
				(pads allowed)
				(copperpour not_allowed)
				(footprints allowed)
			)
			(placement
				(enabled no)
				(sheetname "")
			)
			(fill
				(thermal_gap 0.5)
				(thermal_bridge_width 0.5)
				(island_removal_mode 0)
			)
			(polygon
				(pts
					(arc
						(start 462.59242 -127.627888)
						(mid 458.40142 -127.627888)
						(end 462.59242 -127.627888)
					)
				)
			)
		)
	)
	(footprint ""
		(layer "F.Cu")
		(at 116.84508 -400.414998 -90)
		(property "Reference" "R3510"
			(at 0 0 270)
			(layer "F.SilkS")
			(hide yes)
			(effects
				(font
					(size 1.27 1.27)
				)
			)
		)
		(property "Value" ""
			(at 0 0 270)
			(layer "F.Fab")
			(effects
				(font
					(size 1.27 1.27)
				)
			)
		)
		(duplicate_pad_numbers_are_jumpers no)
		(fp_line
			(start -0.7874 0.4064)
			(end -0.7874 -0.4064)
			(stroke
				(width 0.1524)
				(type default)
			)
			(layer "F.SilkS")
		)
		(fp_line
			(start 0.7874 0.4064)
			(end -0.7874 0.4064)
			(stroke
				(width 0.1524)
				(type default)
			)
			(layer "F.SilkS")
		)
		(fp_line
			(start -0.7874 -0.4064)
			(end 0.7874 -0.4064)
			(stroke
				(width 0.1524)
				(type default)
			)
			(layer "F.SilkS")
		)
		(fp_line
			(start 0.7874 -0.4064)
			(end 0.7874 0.4064)
			(stroke
				(width 0.1524)
				(type default)
			)
			(layer "F.SilkS")
		)
		(fp_line
			(start -0.67945 0.3048)
			(end -0.67945 -0.305054)
			(stroke
				(width 0.1)
				(type default)
			)
			(layer "F.Fab")
		)
		(fp_line
			(start -0.12065 0.3048)
			(end -0.67945 0.3048)
			(stroke
				(width 0.1)
				(type default)
			)
			(layer "F.Fab")
		)
		(fp_line
			(start 0.120396 0.3048)
			(end 0.120396 0.2794)
			(stroke
				(width 0.1)
				(type default)
			)
			(layer "F.Fab")
		)
		(fp_line
			(start 0.67945 0.3048)
			(end 0.120396 0.3048)
			(stroke
				(width 0.1)
				(type default)
			)
			(layer "F.Fab")
		)
		(fp_line
			(start -0.12065 0.2794)
			(end -0.12065 0.3048)
			(stroke
				(width 0.1)
				(type default)
			)
			(layer "F.Fab")
		)
		(fp_line
			(start 0.120396 0.2794)
			(end -0.12065 0.2794)
			(stroke
				(width 0.1)
				(type default)
			)
			(layer "F.Fab")
		)
		(fp_line
			(start -0.12065 -0.2794)
			(end 0.12065 -0.2794)
			(stroke
				(width 0.1)
				(type default)
			)
			(layer "F.Fab")
		)
		(fp_line
			(start 0.12065 -0.2794)
			(end 0.12065 -0.3048)
			(stroke
				(width 0.1)
				(type default)
			)
			(layer "F.Fab")
		)
		(fp_line
			(start 0.12065 -0.3048)
			(end 0.67945 -0.3048)
			(stroke
				(width 0.1)
				(type default)
			)
			(layer "F.Fab")
		)
		(fp_line
			(start 0.67945 -0.3048)
			(end 0.67945 0.3048)
			(stroke
				(width 0.1)
				(type default)
			)
			(layer "F.Fab")
		)
		(fp_line
			(start -0.67945 -0.305054)
			(end -0.12065 -0.305054)
			(stroke
				(width 0.1)
				(type default)
			)
			(layer "F.Fab")
		)
		(fp_line
			(start -0.12065 -0.305054)
			(end -0.12065 -0.2794)
			(stroke
				(width 0.1)
				(type default)
			)
			(layer "F.Fab")
		)
		(pad "1" smd circle
			(at -0.40005 0 270)
			(size 0 0)
			(layers "F.Cu" "F.Mask" "F.Paste")
			(net "P3V3_AUX")
		)
		(pad "2" smd circle
			(at 0.40005 0 270)
			(size 0 0)
			(layers "F.Cu" "F.Mask" "F.Paste")
			(net "FM_SMB_1_ALERT_GPU_N")
		)
	)
	(footprint ""
		(layer "F.Cu")
		(at 424.204892 -394.603478 180)
		(property "Reference" "C1976"
			(at 0 0 180)
			(layer "F.SilkS")
			(hide yes)
			(effects
				(font
					(size 1.27 1.27)
				)
			)
		)
		(property "Value" ""
			(at 0 0 180)
			(layer "F.Fab")
			(effects
				(font
					(size 1.27 1.27)
				)
			)
		)
		(duplicate_pad_numbers_are_jumpers no)
		(fp_line
			(start 0.7874 0.4064)
			(end -0.7874 0.4064)
			(stroke
				(width 0.1524)
				(type default)
			)
			(layer "F.SilkS")
		)
		(fp_line
			(start 0.7874 -0.4064)
			(end 0.7874 0.4064)
			(stroke
				(width 0.1524)
				(type default)
			)
			(layer "F.SilkS")
		)
		(fp_line
			(start -0.7874 0.4064)
			(end -0.7874 -0.4064)
			(stroke
				(width 0.1524)
				(type default)
			)
			(layer "F.SilkS")
		)
		(fp_line
			(start -0.7874 -0.4064)
			(end 0.7874 -0.4064)
			(stroke
				(width 0.1524)
				(type default)
			)
			(layer "F.SilkS")
		)
		(fp_line
			(start 0.67945 0.3048)
			(end 0.120396 0.3048)
			(stroke
				(width 0.1)
				(type default)
			)
			(layer "F.Fab")
		)
		(fp_line
			(start 0.67945 -0.3048)
			(end 0.67945 0.3048)
			(stroke
				(width 0.1)
				(type default)
			)
			(layer "F.Fab")
		)
		(fp_line
			(start 0.12065 -0.2794)
			(end 0.12065 -0.3048)
			(stroke
				(width 0.1)
				(type default)
			)
			(layer "F.Fab")
		)
		(fp_line
			(start 0.12065 -0.3048)
			(end 0.67945 -0.3048)
			(stroke
				(width 0.1)
				(type default)
			)
			(layer "F.Fab")
		)
		(fp_line
			(start 0.120396 0.3048)
			(end 0.120396 0.2794)
			(stroke
				(width 0.1)
				(type default)
			)
			(layer "F.Fab")
		)
		(fp_line
			(start 0.120396 0.2794)
			(end -0.12065 0.2794)
			(stroke
				(width 0.1)
				(type default)
			)
			(layer "F.Fab")
		)
		(fp_line
			(start -0.12065 0.3048)
			(end -0.67945 0.3048)
			(stroke
				(width 0.1)
				(type default)
			)
			(layer "F.Fab")
		)
		(fp_line
			(start -0.12065 0.2794)
			(end -0.12065 0.3048)
			(stroke
				(width 0.1)
				(type default)
			)
			(layer "F.Fab")
		)
		(fp_line
			(start -0.12065 -0.2794)
			(end 0.12065 -0.2794)
			(stroke
				(width 0.1)
				(type default)
			)
			(layer "F.Fab")
		)
		(fp_line
			(start -0.12065 -0.305054)
			(end -0.12065 -0.2794)
			(stroke
				(width 0.1)
				(type default)
			)
			(layer "F.Fab")
		)
		(fp_line
			(start -0.67945 0.3048)
			(end -0.67945 -0.305054)
			(stroke
				(width 0.1)
				(type default)
			)
			(layer "F.Fab")
		)
		(fp_line
			(start -0.67945 -0.305054)
			(end -0.12065 -0.305054)
			(stroke
				(width 0.1)
				(type default)
			)
			(layer "F.Fab")
		)
		(pad "1" smd circle
			(at -0.40005 0 180)
			(size 0 0)
			(layers "F.Cu" "F.Mask" "F.Paste")
			(net "GPU_FPGA_OVERT_ISO_N")
		)
		(pad "2" smd circle
			(at 0.40005 0 180)
			(size 0 0)
			(layers "F.Cu" "F.Mask" "F.Paste")
			(net "GND")
		)
	)
	(footprint ""
		(layer "F.Cu")
		(at 160.311084 -81.91246 -90)
		(property "Reference" "R3224"
			(at 0 0 270)
			(layer "F.SilkS")
			(hide yes)
			(effects
				(font
					(size 1.27 1.27)
				)
			)
		)
		(property "Value" ""
			(at 0 0 270)
			(layer "F.Fab")
			(effects
				(font
					(size 1.27 1.27)
				)
			)
		)
		(duplicate_pad_numbers_are_jumpers no)
		(fp_line
			(start -0.7874 0.4064)
			(end -0.7874 -0.4064)
			(stroke
				(width 0.1524)
				(type default)
			)
			(layer "F.SilkS")
		)
		(fp_line
			(start 0.7874 0.4064)
			(end -0.7874 0.4064)
			(stroke
				(width 0.1524)
				(type default)
			)
			(layer "F.SilkS")
		)
		(fp_line
			(start -0.7874 -0.4064)
			(end 0.7874 -0.4064)
			(stroke
				(width 0.1524)
				(type default)
			)
			(layer "F.SilkS")
		)
		(fp_line
			(start 0.7874 -0.4064)
			(end 0.7874 0.4064)
			(stroke
				(width 0.1524)
				(type default)
			)
			(layer "F.SilkS")
		)
		(fp_line
			(start -0.67945 0.3048)
			(end -0.67945 -0.305054)
			(stroke
				(width 0.1)
				(type default)
			)
			(layer "F.Fab")
		)
		(fp_line
			(start -0.12065 0.3048)
			(end -0.67945 0.3048)
			(stroke
				(width 0.1)
				(type default)
			)
			(layer "F.Fab")
		)
		(fp_line
			(start 0.120396 0.3048)
			(end 0.120396 0.2794)
			(stroke
				(width 0.1)
				(type default)
			)
			(layer "F.Fab")
		)
		(fp_line
			(start 0.67945 0.3048)
			(end 0.120396 0.3048)
			(stroke
				(width 0.1)
				(type default)
			)
			(layer "F.Fab")
		)
		(fp_line
			(start -0.12065 0.2794)
			(end -0.12065 0.3048)
			(stroke
				(width 0.1)
				(type default)
			)
			(layer "F.Fab")
		)
		(fp_line
			(start 0.120396 0.2794)
			(end -0.12065 0.2794)
			(stroke
				(width 0.1)
				(type default)
			)
			(layer "F.Fab")
		)
		(fp_line
			(start -0.12065 -0.2794)
			(end 0.12065 -0.2794)
			(stroke
				(width 0.1)
				(type default)
			)
			(layer "F.Fab")
		)
		(fp_line
			(start 0.12065 -0.2794)
			(end 0.12065 -0.3048)
			(stroke
				(width 0.1)
				(type default)
			)
			(layer "F.Fab")
		)
		(fp_line
			(start 0.12065 -0.3048)
			(end 0.67945 -0.3048)
			(stroke
				(width 0.1)
				(type default)
			)
			(layer "F.Fab")
		)
		(fp_line
			(start 0.67945 -0.3048)
			(end 0.67945 0.3048)
			(stroke
				(width 0.1)
				(type default)
			)
			(layer "F.Fab")
		)
		(fp_line
			(start -0.67945 -0.305054)
			(end -0.12065 -0.305054)
			(stroke
				(width 0.1)
				(type default)
			)
			(layer "F.Fab")
		)
		(fp_line
			(start -0.12065 -0.305054)
			(end -0.12065 -0.2794)
			(stroke
				(width 0.1)
				(type default)
			)
			(layer "F.Fab")
		)
		(pad "1" smd circle
			(at -0.40005 0 270)
			(size 0 0)
			(layers "F.Cu" "F.Mask" "F.Paste")
			(net "SMB_S3M_CPU1_PIROM_3V3AUX_SCL")
		)
		(pad "2" smd circle
			(at 0.40005 0 270)
			(size 0 0)
			(layers "F.Cu" "F.Mask" "F.Paste")
			(net "P3V3_AUX")
		)
	)
)
